(kicad_pcb
	(version 20260206)
	(generator "pcbnew")
	(generator_version "10.0")
	(general
		(thickness 1.6)
		(legacy_teardrops no)
	)
	(paper "A4")
	(title_block
		(title "v1-chassis-manager — T6M_CM_d_v01_1031_1645.brd")
		(comment 1 "Open CloudServer (Microsoft) / footprints 662-667 of 2512")
	)
	(layers
		(0 "F.Cu" signal "TOP")
		(4 "In1.Cu" signal "GND1")
		(6 "In2.Cu" signal "IN1")
		(8 "In3.Cu" signal "VCC1")
		(10 "In4.Cu" signal "VCC2")
		(12 "In5.Cu" signal "GND2")
		(14 "In6.Cu" signal "IN2")
		(16 "In7.Cu" signal "IN3")
		(18 "In8.Cu" signal "GND3")
		(2 "B.Cu" signal "BOTTOM")
		(9 "F.Adhes" user "F.Adhesive")
		(11 "B.Adhes" user "B.Adhesive")
		(13 "F.Paste" user "Package Geometry/Pastemask Top")
		(15 "B.Paste" user "Package Geometry/Pastemask Bottom")
		(5 "F.SilkS" user "Ref Des/Silkscreen Top")
		(7 "B.SilkS" user "Ref Des/Silkscreen Bottom")
		(1 "F.Mask" user "Board Geometry/Soldermask Top")
		(3 "B.Mask" user "Board Geometry/Soldermask Bottom")
		(17 "Dwgs.User" user "User.Drawings")
		(19 "Cmts.User" user "User.Comments")
		(21 "Eco1.User" user "User.Eco1")
		(23 "Eco2.User" user "User.Eco2")
		(25 "Edge.Cuts" user "Board Geometry/Outline")
		(27 "Margin" user)
		(31 "F.CrtYd" user "Package Geometry/Place Bound Top")
		(29 "B.CrtYd" user "Package Geometry/Place Bound Bottom")
		(35 "F.Fab" user "Ref Des/Assembly Top")
		(33 "B.Fab" user "Ref Des/Assembly Bottom")
	)
	(footprint ""
		(layer "F.Cu")
		(at 114.393218 -138.394694 -90)
		(property "Reference" "PC109"
			(at -3.238246 -3.335528 90)
			(unlocked yes)
			(layer "F.SilkS")
			(effects
				(font
					(size 0.635 0.4064)
					(thickness 0.1524)
				)
				(justify left)
			)
		)
		(property "Value" ""
			(at 0 0 270)
			(layer "F.Fab")
			(effects
				(font
					(size 1.27 1.27)
				)
			)
		)
		(duplicate_pad_numbers_are_jumpers no)
		(fp_line
			(start -0.7874 0.4064)
			(end -0.7874 -0.4064)
			(stroke
				(width 0.1524)
				(type default)
			)
			(layer "F.SilkS")
		)
		(fp_line
			(start 0.7874 0.4064)
			(end -0.7874 0.4064)
			(stroke
				(width 0.1524)
				(type default)
			)
			(layer "F.SilkS")
		)
		(fp_line
			(start 0 0.381)
			(end 0 -0.381)
			(stroke
				(width 0.1524)
				(type default)
			)
			(layer "F.SilkS")
		)
		(fp_line
			(start -0.7874 -0.4064)
			(end 0.7874 -0.4064)
			(stroke
				(width 0.1524)
				(type default)
			)
			(layer "F.SilkS")
		)
		(fp_line
			(start 0.7874 -0.4064)
			(end 0.7874 0.4064)
			(stroke
				(width 0.1524)
				(type default)
			)
			(layer "F.SilkS")
		)
		(fp_poly
			(pts
				(xy -0.5334 0.254) (xy -0.635 0.254) (xy -0.635 0.2286) (xy -0.635 -0.254) (xy -0.5334 -0.254) (xy -0.5334 -0.2794)
				(xy 0.5334 -0.2794) (xy 0.5334 -0.254) (xy 0.635 -0.254) (xy 0.635 0.254) (xy 0.5334 0.254) (xy 0.5334 0.2794)
				(xy -0.508 0.2794) (xy -0.5334 0.2794)
			)
			(stroke
				(width 0)
				(type default)
			)
			(fill no)
			(layer "F.CrtYd")
		)
		(pad "1" smd rect
			(at 0.40005 0 270)
			(size 0.4572 0.508)
			(layers "F.Cu" "F.Mask" "F.Paste")
			(net "VR_PVCCP_NODE1_RGND")
		)
		(pad "2" smd rect
			(at -0.40005 0 270)
			(size 0.4572 0.508)
			(layers "F.Cu" "F.Mask" "F.Paste")
			(net "VR_PVCCP_NODE1_VSEN")
		)
	)
	(footprint ""
		(layer "F.Cu")
		(at 94.451932 -169.203624)
		(property "Reference" "R757"
			(at 86.67369 74.174096 0)
			(unlocked yes)
			(layer "F.SilkS")
			(effects
				(font
					(size 0.7874 0.5842)
					(thickness 0.1524)
				)
				(justify left)
			)
		)
		(property "Value" ""
			(at 0 0 0)
			(layer "F.Fab")
			(effects
				(font
					(size 1.27 1.27)
				)
			)
		)
		(duplicate_pad_numbers_are_jumpers no)
		(fp_line
			(start -0.7874 -0.4064)
			(end 0.7874 -0.4064)
			(stroke
				(width 0.1524)
				(type default)
			)
			(layer "F.SilkS")
		)
		(fp_line
			(start -0.7874 0.4064)
			(end -0.7874 -0.4064)
			(stroke
				(width 0.1524)
				(type default)
			)
			(layer "F.SilkS")
		)
		(fp_line
			(start 0.7874 -0.4064)
			(end 0.7874 0.4064)
			(stroke
				(width 0.1524)
				(type default)
			)
			(layer "F.SilkS")
		)
		(fp_line
			(start 0.7874 0.4064)
			(end -0.7874 0.4064)
			(stroke
				(width 0.1524)
				(type default)
			)
			(layer "F.SilkS")
		)
		(fp_poly
			(pts
				(xy -0.508 0.2794) (xy -0.508 0.2286) (xy -0.635 0.2286) (xy -0.635 -0.254) (xy -0.5334 -0.254)
				(xy -0.5334 -0.2794) (xy 0.5334 -0.2794) (xy 0.5334 -0.254) (xy 0.635 -0.254) (xy 0.635 0.254) (xy 0.5334 0.254)
				(xy 0.5334 0.2794)
			)
			(stroke
				(width 0)
				(type default)
			)
			(fill no)
			(layer "F.CrtYd")
		)
		(pad "1" smd rect
			(at 0.40005 0)
			(size 0.4572 0.508)
			(layers "F.Cu" "F.Mask" "F.Paste")
			(net "FAN2_TACH_IN")
		)
		(pad "2" smd rect
			(at -0.40005 0)
			(size 0.4572 0.508)
			(layers "F.Cu" "F.Mask" "F.Paste")
			(net "FAN2_TACH")
		)
	)
	(footprint ""
		(layer "F.Cu")
		(at 142.910052 -133.17855)
		(property "Reference" "R289"
			(at -3.280918 3.102864 0)
			(unlocked yes)
			(layer "F.SilkS")
			(effects
				(font
					(size 0.7874 0.5842)
					(thickness 0.1524)
				)
				(justify left)
			)
		)
		(property "Value" ""
			(at 0 0 0)
			(layer "F.Fab")
			(effects
				(font
					(size 1.27 1.27)
				)
			)
		)
		(duplicate_pad_numbers_are_jumpers no)
		(fp_line
			(start -0.7874 -0.4064)
			(end 0.7874 -0.4064)
			(stroke
				(width 0.1524)
				(type default)
			)
			(layer "F.SilkS")
		)
		(fp_line
			(start -0.7874 0.4064)
			(end -0.7874 -0.4064)
			(stroke
				(width 0.1524)
				(type default)
			)
			(layer "F.SilkS")
		)
		(fp_line
			(start 0.7874 -0.4064)
			(end 0.7874 0.4064)
			(stroke
				(width 0.1524)
				(type default)
			)
			(layer "F.SilkS")
		)
		(fp_line
			(start 0.7874 0.4064)
			(end -0.7874 0.4064)
			(stroke
				(width 0.1524)
				(type default)
			)
			(layer "F.SilkS")
		)
		(fp_poly
			(pts
				(xy -0.508 0.2794) (xy -0.508 0.2286) (xy -0.635 0.2286) (xy -0.635 -0.254) (xy -0.5334 -0.254)
				(xy -0.5334 -0.2794) (xy 0.5334 -0.2794) (xy 0.5334 -0.254) (xy 0.635 -0.254) (xy 0.635 0.254) (xy 0.5334 0.254)
				(xy 0.5334 0.2794)
			)
			(stroke
				(width 0)
				(type default)
			)
			(fill no)
			(layer "F.CrtYd")
		)
		(pad "1" smd rect
			(at 0.40005 0)
			(size 0.4572 0.508)
			(layers "F.Cu" "F.Mask" "F.Paste")
			(net "GND")
		)
		(pad "2" smd rect
			(at -0.40005 0)
			(size 0.4572 0.508)
			(layers "F.Cu" "F.Mask" "F.Paste")
			(net "PCIE_SW_TEST6")
		)
	)
	(footprint ""
		(layer "F.Cu")
		(at 165.011354 -183.051196 180)
		(property "Reference" "R1172"
			(at 5.204206 -0.410718 0)
			(unlocked yes)
			(layer "F.SilkS")
			(effects
				(font
					(size 0.7874 0.5842)
					(thickness 0.1524)
				)
				(justify left)
			)
		)
		(property "Value" ""
			(at 0 0 180)
			(layer "F.Fab")
			(effects
				(font
					(size 1.27 1.27)
				)
			)
		)
		(duplicate_pad_numbers_are_jumpers no)
		(fp_line
			(start 0.7874 0.4064)
			(end -0.7874 0.4064)
			(stroke
				(width 0.1524)
				(type default)
			)
			(layer "F.SilkS")
		)
		(fp_line
			(start 0.7874 -0.4064)
			(end 0.7874 0.4064)
			(stroke
				(width 0.1524)
				(type default)
			)
			(layer "F.SilkS")
		)
		(fp_line
			(start -0.7874 0.4064)
			(end -0.7874 -0.4064)
			(stroke
				(width 0.1524)
				(type default)
			)
			(layer "F.SilkS")
		)
		(fp_line
			(start -0.7874 -0.4064)
			(end 0.7874 -0.4064)
			(stroke
				(width 0.1524)
				(type default)
			)
			(layer "F.SilkS")
		)
		(fp_poly
			(pts
				(xy -0.508 0.2794) (xy -0.508 0.2286) (xy -0.635 0.2286) (xy -0.635 -0.254) (xy -0.5334 -0.254)
				(xy -0.5334 -0.2794) (xy 0.5334 -0.2794) (xy 0.5334 -0.254) (xy 0.635 -0.254) (xy 0.635 0.254) (xy 0.5334 0.254)
				(xy 0.5334 0.2794)
			)
			(stroke
				(width 0)
				(type default)
			)
			(fill no)
			(layer "F.CrtYd")
		)
		(pad "1" smd rect
			(at 0.40005 0 180)
			(size 0.4572 0.508)
			(layers "F.Cu" "F.Mask" "F.Paste")
			(net "CPLD_UART_RTS_P3_N")
		)
		(pad "2" smd rect
			(at -0.40005 0 180)
			(size 0.4572 0.508)
			(layers "F.Cu" "F.Mask" "F.Paste")
			(net "GND")
		)
	)
	(footprint ""
		(layer "F.Cu")
		(at 183.71185 -63.058294 90)
		(property "Reference" "J15"
			(at -8.60171 4.64947 0)
			(unlocked yes)
			(layer "F.SilkS")
			(effects
				(font
					(size 0.7874 0.5842)
					(thickness 0.1524)
				)
				(justify left)
			)
		)
		(property "Value" ""
			(at 0 0 90)
			(layer "F.Fab")
			(effects
				(font
					(size 1.27 1.27)
				)
			)
		)
		(duplicate_pad_numbers_are_jumpers no)
		(fp_line
			(start 4.953 -3.9878)
			(end -4.953 -3.9878)
			(stroke
				(width 0.1524)
				(type default)
			)
			(layer "F.SilkS")
		)
		(fp_line
			(start -7.62 -1.3716)
			(end -7.62 1.1176)
			(stroke
				(width 0.1524)
				(type default)
			)
			(layer "F.SilkS")
		)
		(fp_line
			(start 7.62 1.1176)
			(end 7.62 -1.3716)
			(stroke
				(width 0.1524)
				(type default)
			)
			(layer "F.SilkS")
		)
		(fp_line
			(start -7.62 4.318)
			(end -7.62 14.3764)
			(stroke
				(width 0.1524)
				(type default)
			)
			(layer "F.SilkS")
		)
		(fp_line
			(start 7.62 14.3764)
			(end 7.62 4.318)
			(stroke
				(width 0.1524)
				(type default)
			)
			(layer "F.SilkS")
		)
		(fp_line
			(start -7.62 14.3764)
			(end 7.62 14.3764)
			(stroke
				(width 0.1524)
				(type default)
			)
			(layer "F.SilkS")
		)
		(fp_poly
			(pts
				(xy -7.655052 0.031242) (xy -9.560052 -0.730758) (xy -9.560052 0.793242)
			)
			(stroke
				(width 0)
				(type default)
			)
			(fill yes)
			(layer "F.SilkS")
		)
		(fp_poly
			(pts
				(xy -4.2926 -3.4036) (xy 4.2926 -3.4036) (xy 4.2926 -1.8288) (xy -4.2926 -1.8288)
			)
			(stroke
				(width 0)
				(type default)
			)
			(fill no)
			(layer "B.CrtYd")
		)
		(fp_poly
			(pts
				(xy 4.2926 -0.7874) (xy -4.2926 -0.7874) (xy -4.2926 0.7874) (xy 4.2926 0.7874)
			)
			(stroke
				(width 0)
				(type default)
			)
			(fill no)
			(layer "B.CrtYd")
		)
		(fp_poly
			(pts
				(arc
					(start 6.5659 -4.8006)
					(mid 5.272743 -4.264957)
					(end 4.7371 -2.9718)
				)
				(arc
					(start 4.7371 -2.9464)
					(mid 5.265304 -1.671204)
					(end 6.5405 -1.143)
				)
				(arc
					(start 6.5913 -1.143)
					(mid 8.4201 -2.9718)
					(end 6.5913 -4.8006)
				)
			)
			(stroke
				(width 0)
				(type default)
			)
			(fill no)
			(layer "B.CrtYd")
		)
		(fp_poly
			(pts
				(arc
					(start -6.5786 -4.8006)
					(mid -7.871757 -4.264957)
					(end -8.4074 -2.9718)
				)
				(arc
					(start -8.4074 -2.9464)
					(mid -7.879196 -1.671204)
					(end -6.604 -1.143)
				)
				(arc
					(start -6.5532 -1.143)
					(mid -4.7244 -2.9718)
					(end -6.5532 -4.8006)
				)
			)
			(stroke
				(width 0)
				(type default)
			)
			(fill no)
			(layer "B.CrtYd")
		)
		(fp_poly
			(pts
				(arc
					(start 6.5659 0.889)
					(mid 5.272743 1.424643)
					(end 4.7371 2.7178)
				)
				(arc
					(start 4.7371 2.7432)
					(mid 5.265304 4.018396)
					(end 6.5405 4.5466)
				)
				(arc
					(start 6.5913 4.5466)
					(mid 8.4201 2.7178)
					(end 6.5913 0.889)
				)
			)
			(stroke
				(width 0)
				(type default)
			)
			(fill no)
			(layer "B.CrtYd")
		)
		(fp_poly
			(pts
				(arc
					(start -6.5913 0.889)
					(mid -7.884457 1.424643)
					(end -8.4201 2.7178)
				)
				(arc
					(start -8.4201 2.7432)
					(mid -7.891896 4.018396)
					(end -6.6167 4.5466)
				)
				(arc
					(start -6.5659 4.5466)
					(mid -4.7371 2.7178)
					(end -6.5659 0.889)
				)
			)
			(stroke
				(width 0)
				(type default)
			)
			(fill no)
			(layer "B.CrtYd")
		)
		(fp_rect
			(start -8.7376 14.4526)
			(end 8.7376 -4.9276)
			(stroke
				(width 0)
				(type default)
			)
			(fill no)
			(layer "F.CrtYd")
		)
		(fp_line
			(start 7.62 -3.9878)
			(end 7.62 14.3764)
			(stroke
				(width 0.1)
				(type default)
			)
			(layer "F.Fab")
		)
		(fp_line
			(start -7.62 -3.9878)
			(end 7.62 -3.9878)
			(stroke
				(width 0.1)
				(type default)
			)
			(layer "F.Fab")
		)
		(fp_line
			(start -7.62 4.318)
			(end -7.62 -3.9878)
			(stroke
				(width 0.1)
				(type default)
			)
			(layer "F.Fab")
		)
		(fp_line
			(start 7.62 14.3764)
			(end -7.62 14.3764)
			(stroke
				(width 0.1)
				(type default)
			)
			(layer "F.Fab")
		)
		(fp_line
			(start -7.62 14.3764)
			(end -7.62 4.318)
			(stroke
				(width 0.1)
				(type default)
			)
			(layer "F.Fab")
		)
		(fp_poly
			(pts
				(xy -8.5725 0) (xy -10.4775 -0.762) (xy -10.4775 0.762)
			)
			(stroke
				(width 0)
				(type default)
			)
			(fill yes)
			(layer "F.Fab")
		)
		(fp_text user "8"
			(at 4.047998 -5.137912 0)
			(unlocked yes)
			(layer "F.SilkS")
			(effects
				(font
					(size 0.7874 0.5842)
					(thickness 0.1524)
				)
				(justify left)
			)
		)
		(fp_text user "5"
			(at -4.461002 -4.756912 0)
			(unlocked yes)
			(layer "F.SilkS")
			(effects
				(font
					(size 0.7874 0.5842)
					(thickness 0.1524)
				)
				(justify left)
			)
		)
		(fp_text user "1"
			(at -8.271002 -0.819912 0)
			(unlocked yes)
			(layer "F.SilkS")
			(effects
				(font
					(size 0.7874 0.5842)
					(thickness 0.1524)
				)
				(justify left)
			)
		)
		(fp_text user "4"
			(at 8.226806 -0.026416 0)
			(unlocked yes)
			(layer "F.SilkS")
			(effects
				(font
					(size 0.7874 0.5842)
					(thickness 0.1524)
				)
				(justify left)
			)
		)
		(fp_text user "8"
			(at 3.557524 -3.736594 0)
			(unlocked yes)
			(layer "B.SilkS")
			(effects
				(font
					(size 0.7874 0.5842)
					(thickness 0.1524)
				)
				(justify left mirror)
			)
		)
		(fp_text user "5"
			(at -3.50647 -3.736594 0)
			(unlocked yes)
			(layer "B.SilkS")
			(effects
				(font
					(size 0.7874 0.5842)
					(thickness 0.1524)
				)
				(justify left mirror)
			)
		)
		(fp_text user "1"
			(at -3.482848 1.549654 0)
			(unlocked yes)
			(layer "B.SilkS")
			(effects
				(font
					(size 0.7874 0.5842)
					(thickness 0.1524)
				)
				(justify left mirror)
			)
		)
		(fp_text user "4"
			(at 3.60426 1.736852 0)
			(unlocked yes)
			(layer "B.SilkS")
			(effects
				(font
					(size 0.7874 0.5842)
					(thickness 0.1524)
				)
				(justify left mirror)
			)
		)
		(fp_text user "8"
			(at 3.9624 -5.5372 90)
			(unlocked yes)
			(layer "B.Fab")
			(effects
				(font
					(size 1.016 0.762)
					(thickness 0.000001)
				)
				(justify left mirror)
			)
		)
		(fp_text user "5"
			(at -3.0734 -5.5372 90)
			(unlocked yes)
			(layer "B.Fab")
			(effects
				(font
					(size 1.016 0.762)
					(thickness 0.000001)
				)
				(justify left mirror)
			)
		)
		(fp_text user "4"
			(at 5.334 -0.118618 90)
			(unlocked yes)
			(layer "B.Fab")
			(effects
				(font
					(size 1.016 0.762)
					(thickness 0.000001)
				)
				(justify left mirror)
			)
		)
		(fp_text user "1"
			(at -4.572 -0.118618 90)
			(unlocked yes)
			(layer "B.Fab")
			(effects
				(font
					(size 1.016 0.762)
					(thickness 0.000001)
				)
				(justify left mirror)
			)
		)
		(fp_text user "8"
			(at 3.175 -5.5372 90)
			(unlocked yes)
			(layer "F.Fab")
			(effects
				(font
					(size 1.016 0.762)
					(thickness 0.000001)
				)
				(justify left)
			)
		)
		(fp_text user "5"
			(at -3.81 -5.5372 90)
			(unlocked yes)
			(layer "F.Fab")
			(effects
				(font
					(size 1.016 0.762)
					(thickness 0.000001)
				)
				(justify left)
			)
		)
		(fp_text user "4"
			(at 8.001 -0.118618 90)
			(unlocked yes)
			(layer "F.Fab")
			(effects
				(font
					(size 1.016 0.762)
					(thickness 0.000001)
				)
				(justify left)
			)
		)
		(fp_text user "1"
			(at -8.763 -0.118618 90)
			(unlocked yes)
			(layer "F.Fab")
			(effects
				(font
					(size 1.016 0.762)
					(thickness 0.000001)
				)
				(justify left)
			)
		)
		(pad "1" thru_hole rect
			(at -3.5052 0 90)
			(size 1.4732 1.4732)
			(drill 1.016)
			(layers "*.Cu" "*.Mask")
			(remove_unused_layers no)
			(net "USBPWR_P1")
			(clearance 0.0254)
			(thermal_gap 0.0254)
			(padstack
				(mode front_inner_back)
				(layer "Inner"
					(shape circle)
					(size 1.4732 1.4732)
					(clearance 0.0254)
				)
				(layer "B.Cu"
					(shape rect)
					(size 1.4732 1.4732)
					(clearance 0.0254)
				)
			)
		)
		(pad "2" thru_hole circle
			(at -1.016 0 90)
			(size 1.4732 1.4732)
			(drill 1.016)
			(layers "*.Cu" "*.Mask")
			(remove_unused_layers no)
			(net "USB2_L_DN")
			(clearance 0.0254)
			(thermal_gap 0.0254)
		)
		(pad "3" thru_hole circle
			(at 1.016 0 90)
			(size 1.4732 1.4732)
			(drill 1.016)
			(layers "*.Cu" "*.Mask")
			(remove_unused_layers no)
			(net "USB2_L_DP")
			(clearance 0.0254)
			(thermal_gap 0.0254)
		)
		(pad "4" thru_hole circle
			(at 3.5052 0 90)
			(size 1.4732 1.4732)
			(drill 1.016)
			(layers "*.Cu" "*.Mask")
			(remove_unused_layers no)
			(net "GND")
			(clearance 0.0254)
			(thermal_gap 0.0254)
		)
		(pad "5" thru_hole circle
			(at -3.5052 -2.6162 90)
			(size 1.4732 1.4732)
			(drill 1.016)
			(layers "*.Cu" "*.Mask")
			(remove_unused_layers no)
			(net "USBPWR_P1")
			(clearance 0.0254)
			(thermal_gap 0.0254)
		)
		(pad "6" thru_hole circle
			(at -1.016 -2.6162 90)
			(size 1.4732 1.4732)
			(drill 1.016)
			(layers "*.Cu" "*.Mask")
			(remove_unused_layers no)
			(net "USB3_L_DN")
			(clearance 0.0254)
			(thermal_gap 0.0254)
		)
		(pad "7" thru_hole circle
			(at 1.016 -2.6162 90)
			(size 1.4732 1.4732)
			(drill 1.016)
			(layers "*.Cu" "*.Mask")
			(remove_unused_layers no)
			(net "USB3_L_DP")
			(clearance 0.0254)
			(thermal_gap 0.0254)
		)
		(pad "8" thru_hole circle
			(at 3.5052 -2.6162 90)
			(size 1.4732 1.4732)
			(drill 1.016)
			(layers "*.Cu" "*.Mask")
			(remove_unused_layers no)
			(net "GND")
			(clearance 0.0254)
			(thermal_gap 0.0254)
		)
		(pad "9" thru_hole circle
			(at -6.5786 2.7178 90)
			(size 3.556 3.556)
			(drill 2.286)
			(layers "*.Cu" "*.Mask")
			(remove_unused_layers no)
			(net "GND")
			(clearance -0.381)
		)
		(pad "10" thru_hole circle
			(at 6.5786 2.7178 90)
			(size 3.556 3.556)
			(drill 2.286)
			(layers "*.Cu" "*.Mask")
			(remove_unused_layers no)
			(net "GND")
			(clearance -0.381)
		)
		(pad "11" thru_hole circle
			(at -6.5786 -2.9718 90)
			(size 3.556 3.556)
			(drill 2.286)
			(layers "*.Cu" "*.Mask")
			(remove_unused_layers no)
			(net "GND")
			(clearance -0.381)
		)
		(pad "12" thru_hole circle
			(at 6.5786 -2.9718 90)
			(size 3.556 3.556)
			(drill 2.286)
			(layers "*.Cu" "*.Mask")
			(remove_unused_layers no)
			(net "GND")
			(clearance -0.381)
		)
	)
	(footprint ""
		(layer "F.Cu")
		(at 137.593578 -60.704222 180)
		(property "Reference" "R511"
			(at 0.823214 -4.858512 0)
			(unlocked yes)
			(layer "F.SilkS")
			(effects
				(font
					(size 0.7874 0.5842)
					(thickness 0.1524)
				)
				(justify left)
			)
		)
		(property "Value" ""
			(at 0 0 180)
			(layer "F.Fab")
			(effects
				(font
					(size 1.27 1.27)
				)
			)
		)
		(duplicate_pad_numbers_are_jumpers no)
		(fp_line
			(start 0.7874 0.4064)
			(end -0.7874 0.4064)
			(stroke
				(width 0.1524)
				(type default)
			)
			(layer "F.SilkS")
		)
		(fp_line
			(start 0.7874 -0.4064)
			(end 0.7874 0.4064)
			(stroke
				(width 0.1524)
				(type default)
			)
			(layer "F.SilkS")
		)
		(fp_line
			(start -0.7874 0.4064)
			(end -0.7874 -0.4064)
			(stroke
				(width 0.1524)
				(type default)
			)
			(layer "F.SilkS")
		)
		(fp_line
			(start -0.7874 -0.4064)
			(end 0.7874 -0.4064)
			(stroke
				(width 0.1524)
				(type default)
			)
			(layer "F.SilkS")
		)
		(fp_poly
			(pts
				(xy -0.508 0.2794) (xy -0.508 0.2286) (xy -0.635 0.2286) (xy -0.635 -0.254) (xy -0.5334 -0.254)
				(xy -0.5334 -0.2794) (xy 0.5334 -0.2794) (xy 0.5334 -0.254) (xy 0.635 -0.254) (xy 0.635 0.254) (xy 0.5334 0.254)
				(xy 0.5334 0.2794)
			)
			(stroke
				(width 0)
				(type default)
			)
			(fill no)
			(layer "F.CrtYd")
		)
		(pad "1" smd rect
			(at 0.40005 0 180)
			(size 0.4572 0.508)
			(layers "F.Cu" "F.Mask" "F.Paste")
			(net "P3V3_NODE1")
		)
		(pad "2" smd rect
			(at -0.40005 0 180)
			(size 0.4572 0.508)
			(layers "F.Cu" "F.Mask" "F.Paste")
			(net "SATA_NODE1_GPIO2")
		)
	)
)
